# S9S_MB_2U (Grand Teton) — schematic netlist excerpt (pin names and nets, part order shuffled) for the footprints in the layout excerpt that follows; sources: Cadence DE-HDL packaged netlist, KiCad conversion of 03242023_DA0F0TMBIJ0_F0T_Motherboard_J_brd_V01_OCP.brd

R4077  Q_RES  1 1% CHIP  pkg 0402LF  page 212 : A = VFG3P3_CLK_GEN ; B = VFG_3P3A_CLK_GEN

X31  TP_TDR_4P_FTS  TP_TDR_4P_DIP EMPTY  pkg TH  page 309
  S1  = TDR_DIFF_100_IN5_DN
  P1  = T1_GND
  P2  = T1_GND
  S2  = TDR_DIFF_100_IN5_DP

(kicad_pcb
	(version 20260206)
	(generator "pcbnew")
	(generator_version "10.0")
	(general
		(thickness 1.6)
		(legacy_teardrops no)
	)
	(paper "A4")
	(title_block
		(title "03242023_DA0F0TMBIJ0_F0T_Motherboard_J_brd_V01_OCP.brd")
		(comment 1 "Grand Teton / footprints 5722-5723 of 6105")
	)
	(layers
		(0 "F.Cu" signal "TOP")
		(4 "In1.Cu" signal "GND")
		(6 "In2.Cu" signal "IN1")
		(8 "In3.Cu" signal "GND1")
		(10 "In4.Cu" signal "IN2")
		(12 "In5.Cu" signal "GND2")
		(14 "In6.Cu" signal "IN3")
		(16 "In7.Cu" signal "GND3")
		(18 "In8.Cu" signal "VCC")
		(20 "In9.Cu" signal "VCC1")
		(22 "In10.Cu" signal "GND4")
		(24 "In11.Cu" signal "IN4")
		(26 "In12.Cu" signal "GND5")
		(28 "In13.Cu" signal "IN5")
		(30 "In14.Cu" signal "GND6")
		(32 "In15.Cu" signal "IN6")
		(34 "In16.Cu" signal "GND7")
		(2 "B.Cu" signal "BOTTOM")
		(9 "F.Adhes" user "F.Adhesive")
		(11 "B.Adhes" user "B.Adhesive")
		(13 "F.Paste" user "Package Geometry/Pastemask Top")
		(15 "B.Paste" user "Package Geometry/Pastemask Bottom")
		(5 "F.SilkS" user "Ref Des/Silkscreen Top")
		(7 "B.SilkS" user "Ref Des/Silkscreen Bottom")
		(1 "F.Mask" user "Board Geometry/Soldermask Top")
		(3 "B.Mask" user "Board Geometry/Soldermask Bottom")
		(17 "Dwgs.User" user "User.Drawings")
		(19 "Cmts.User" user "User.Comments")
		(21 "Eco1.User" user "User.Eco1")
		(23 "Eco2.User" user "User.Eco2")
		(25 "Edge.Cuts" user "Board Geometry/Outline")
		(27 "Margin" user)
		(31 "F.CrtYd" user "Package Geometry/Place Bound Top")
		(29 "B.CrtYd" user "Package Geometry/Place Bound Bottom")
		(35 "F.Fab" user "Ref Des/Assembly Top")
		(33 "B.Fab" user "Ref Des/Assembly Bottom")
	)
	(footprint ""
		(layer "B.Cu")
		(at 504.058428 2.33172 90)
		(property "Reference" "X31"
			(at 1.48082 3.196082 270)
			(unlocked yes)
			(layer "B.SilkS")
			(effects
				(font
					(size 0.7874 0.5842)
					(thickness 0.1524)
				)
				(justify left mirror)
			)
		)
		(property "Value" ""
			(at 0 0 90)
			(layer "B.Fab")
			(effects
				(font
					(size 1.27 1.27)
				)
				(justify mirror)
			)
		)
		(property "Device Type" "TP_TDR_4P_FTS_TH-TP_TDR_4P_DIPA"
			(at -1.30175 1.27 0)
			(unlocked yes)
			(layer "B.Fab")
			(hide yes)
			(effects
				(font
					(size 0.635 0.4064)
					(thickness 0.1524)
				)
				(justify mirror)
			)
		)
		(property "User Part Number" "N_A"
			(at -1.30175 1.27 0)
			(unlocked yes)
			(layer "Cmts.User")
			(hide yes)
			(effects
				(font
					(size 0.635 0.4064)
					(thickness 0.1524)
				)
				(justify mirror)
			)
		)
		(duplicate_pad_numbers_are_jumpers no)
		(fp_line
			(start 0 -1.27)
			(end 0 -0.635)
			(stroke
				(width 0.1524)
				(type default)
			)
			(layer "B.SilkS")
		)
		(fp_line
			(start -2.54 -1.27)
			(end 0 -1.27)
			(stroke
				(width 0.1524)
				(type default)
			)
			(layer "B.SilkS")
		)
		(fp_line
			(start -2.54 -1.1303)
			(end -2.54 -1.27)
			(stroke
				(width 0.1524)
				(type default)
			)
			(layer "B.SilkS")
		)
		(fp_line
			(start 0 0.635)
			(end 0 1.905)
			(stroke
				(width 0.1524)
				(type default)
			)
			(layer "B.SilkS")
		)
		(fp_line
			(start -2.54 1.4097)
			(end -2.54 1.1303)
			(stroke
				(width 0.1524)
				(type default)
			)
			(layer "B.SilkS")
		)
		(fp_line
			(start 0 3.175)
			(end 0 3.81)
			(stroke
				(width 0.1524)
				(type default)
			)
			(layer "B.SilkS")
		)
		(fp_line
			(start 0 3.81)
			(end -2.54 3.81)
			(stroke
				(width 0.1524)
				(type default)
			)
			(layer "B.SilkS")
		)
		(fp_line
			(start -2.54 3.81)
			(end -2.54 3.6703)
			(stroke
				(width 0.1524)
				(type default)
			)
			(layer "B.SilkS")
		)
		(fp_poly
			(pts
				(xy 2.285746 -0.762) (xy 2.285746 0.762) (xy 0.761746 0)
			)
			(stroke
				(width 0)
				(type default)
			)
			(fill yes)
			(layer "B.SilkS")
		)
		(fp_line
			(start 0 -1.27)
			(end 0 3.81)
			(stroke
				(width 0.1)
				(type default)
			)
			(layer "B.Fab")
		)
		(fp_line
			(start -2.54 -1.27)
			(end 0 -1.27)
			(stroke
				(width 0.1)
				(type default)
			)
			(layer "B.Fab")
		)
		(fp_line
			(start 0 3.81)
			(end -2.54 3.81)
			(stroke
				(width 0.1)
				(type default)
			)
			(layer "B.Fab")
		)
		(fp_line
			(start -2.54 3.81)
			(end -2.54 -1.27)
			(stroke
				(width 0.1)
				(type default)
			)
			(layer "B.Fab")
		)
		(fp_poly
			(pts
				(xy 0.761746 0) (xy 2.285746 -0.762) (xy 2.285746 0.762)
			)
			(stroke
				(width 0)
				(type default)
			)
			(fill yes)
			(layer "B.Fab")
		)
		(pad "1" thru_hole circle
			(at 0 0 270)
			(size 1.0033 1.0033)
			(drill 0.249936)
			(layers "*.Cu" "*.Mask")
			(remove_unused_layers no)
			(net "TDR_DIFF_100_IN5_DN")
			(clearance 0.10795)
			(padstack
				(mode front_inner_back)
				(layer "Inner"
					(shape circle)
					(size 0.8001 0.8001)
					(clearance 0.1524)
				)
				(layer "B.Cu"
					(shape circle)
					(size 1.0033 1.0033)
					(thermal_gap 0.10795)
					(clearance 0.10795)
				)
			)
		)
		(pad "2" thru_hole circle
			(at -2.54 0 270)
			(size 1.9939 1.9939)
			(drill 0.249936)
			(layers "*.Cu" "*.Mask")
			(remove_unused_layers no)
			(net "T1_GND")
			(clearance 0.10795)
			(padstack
				(mode front_inner_back)
				(layer "Inner"
					(shape circle)
					(size 0.8001 0.8001)
					(clearance 0.1524)
				)
				(layer "B.Cu"
					(shape circle)
					(size 1.9939 1.9939)
					(thermal_gap 0.10795)
					(clearance 0.10795)
				)
			)
		)
		(pad "3" thru_hole circle
			(at -2.54 2.54 270)
			(size 1.9939 1.9939)
			(drill 0.249936)
			(layers "*.Cu" "*.Mask")
			(remove_unused_layers no)
			(net "T1_GND")
			(clearance 0.10795)
			(padstack
				(mode front_inner_back)
				(layer "Inner"
					(shape circle)
					(size 0.8001 0.8001)
					(clearance 0.1524)
				)
				(layer "B.Cu"
					(shape circle)
					(size 1.9939 1.9939)
					(thermal_gap 0.10795)
					(clearance 0.10795)
				)
			)
		)
		(pad "4" thru_hole circle
			(at 0 2.54 270)
			(size 1.0033 1.0033)
			(drill 0.249936)
			(layers "*.Cu" "*.Mask")
			(remove_unused_layers no)
			(net "TDR_DIFF_100_IN5_DP")
			(clearance 0.10795)
			(padstack
				(mode front_inner_back)
				(layer "Inner"
					(shape circle)
					(size 0.8001 0.8001)
					(clearance 0.1524)
				)
				(layer "B.Cu"
					(shape circle)
					(size 1.0033 1.0033)
					(thermal_gap 0.10795)
					(clearance 0.10795)
				)
			)
		)
	)
	(footprint ""
		(layer "B.Cu")
		(at 233.5149 -249.182128 -90)
		(property "Reference" "R4077"
			(at 0 0 90)
			(layer "B.SilkS")
			(hide yes)
			(effects
				(font
					(size 1.27 1.27)
				)
				(justify mirror)
			)
		)
		(property "Value" ""
			(at 0 0 90)
			(layer "B.Fab")
			(effects
				(font
					(size 1.27 1.27)
				)
				(justify mirror)
			)
		)
		(duplicate_pad_numbers_are_jumpers no)
		(fp_line
			(start -0.7874 0.4064)
			(end 0.7874 0.4064)
			(stroke
				(width 0.1524)
				(type default)
			)
			(layer "B.SilkS")
		)
		(fp_line
			(start 0.7874 0.4064)
			(end 0.7874 -0.4064)
			(stroke
				(width 0.1524)
				(type default)
			)
			(layer "B.SilkS")
		)
		(fp_line
			(start -0.7874 -0.4064)
			(end -0.7874 0.4064)
			(stroke
				(width 0.1524)
				(type default)
			)
			(layer "B.SilkS")
		)
		(fp_line
			(start 0.7874 -0.4064)
			(end -0.7874 -0.4064)
			(stroke
				(width 0.1524)
				(type default)
			)
			(layer "B.SilkS")
		)
		(fp_line
			(start -0.67945 0.3048)
			(end -0.120396 0.3048)
			(stroke
				(width 0.1)
				(type default)
			)
			(layer "B.Fab")
		)
		(fp_line
			(start -0.120396 0.3048)
			(end -0.120396 0.2794)
			(stroke
				(width 0.1)
				(type default)
			)
			(layer "B.Fab")
		)
		(fp_line
			(start 0.12065 0.3048)
			(end 0.67945 0.3048)
			(stroke
				(width 0.1)
				(type default)
			)
			(layer "B.Fab")
		)
		(fp_line
			(start 0.67945 0.3048)
			(end 0.67945 -0.305054)
			(stroke
				(width 0.1)
				(type default)
			)
			(layer "B.Fab")
		)
		(fp_line
			(start -0.120396 0.2794)
			(end 0.12065 0.2794)
			(stroke
				(width 0.1)
				(type default)
			)
			(layer "B.Fab")
		)
		(fp_line
			(start 0.12065 0.2794)
			(end 0.12065 0.3048)
			(stroke
				(width 0.1)
				(type default)
			)
			(layer "B.Fab")
		)
		(fp_line
			(start -0.12065 -0.2794)
			(end -0.12065 -0.3048)
			(stroke
				(width 0.1)
				(type default)
			)
			(layer "B.Fab")
		)
		(fp_line
			(start 0.12065 -0.2794)
			(end -0.12065 -0.2794)
			(stroke
				(width 0.1)
				(type default)
			)
			(layer "B.Fab")
		)
		(fp_line
			(start -0.67945 -0.3048)
			(end -0.67945 0.3048)
			(stroke
				(width 0.1)
				(type default)
			)
			(layer "B.Fab")
		)
		(fp_line
			(start -0.12065 -0.3048)
			(end -0.67945 -0.3048)
			(stroke
				(width 0.1)
				(type default)
			)
			(layer "B.Fab")
		)
		(fp_line
			(start 0.12065 -0.305054)
			(end 0.12065 -0.2794)
			(stroke
				(width 0.1)
				(type default)
			)
			(layer "B.Fab")
		)
		(fp_line
			(start 0.67945 -0.305054)
			(end 0.12065 -0.305054)
			(stroke
				(width 0.1)
				(type default)
			)
			(layer "B.Fab")
		)
		(pad "1" smd circle
			(at 0.40005 0 90)
			(size 0 0)
			(layers "B.Cu" "B.Mask" "B.Paste")
			(net "VFG3P3_CLK_GEN")
		)
		(pad "2" smd circle
			(at -0.40005 0 90)
			(size 0 0)
			(layers "B.Cu" "B.Mask" "B.Paste")
			(net "VFG_3P3A_CLK_GEN")
		)
	)
)
